# BASEBOARD_FAB2 (Tioga Pass) — schematic netlist excerpt (pin names and nets, part order shuffled) for the footprints in the layout excerpt that follows; sources: Cadence DE-HDL packaged netlist, KiCad conversion of Wiwynn_Tioga_Pass_MB.brd

C6U15  CAP  10UF 4V 20% X6S  pkg 0603LF  page 221 : A = PVDDQ_ABC ; B = GND
C5G59  CAP_A  22.0UF 4V 20% X6S  pkg 0603V  page 242 : A = PVDDQ_DEF ; B = GND
C9R8  CAP_A  22.0UF 4V 20% X6S  pkg 0603V  page 207 : A = PVCCIN_CPU1 ; B = GND
C22W34  SC22U16V5MX-4-GP  20%  pkg SMD-BCG5  page 139 : \1\ = P3V3_STBY ; \2\ = GND

(kicad_pcb
	(version 20260206)
	(generator "pcbnew")
	(generator_version "10.0")
	(general
		(thickness 1.6)
		(legacy_teardrops no)
	)
	(paper "A4")
	(title_block
		(title "Wiwynn_Tioga_Pass_MB.brd")
		(comment 1 "Tioga Pass / footprints 3824-3827 of 4770")
	)
	(layers
		(0 "F.Cu" signal "TOP")
		(4 "In1.Cu" signal "L2GND")
		(6 "In2.Cu" signal "L3")
		(8 "In3.Cu" signal "L4GND")
		(10 "In4.Cu" signal "L5")
		(12 "In5.Cu" signal "L6GND")
		(14 "In6.Cu" signal "L7VCC")
		(16 "In7.Cu" signal "L8VCC")
		(18 "In8.Cu" signal "L9GND")
		(20 "In9.Cu" signal "L10")
		(22 "In10.Cu" signal "L11GND")
		(24 "In11.Cu" signal "L12")
		(26 "In12.Cu" signal "L13GND")
		(2 "B.Cu" signal "BOTTOM")
		(9 "F.Adhes" user "F.Adhesive")
		(11 "B.Adhes" user "B.Adhesive")
		(13 "F.Paste" user "Package Geometry/Pastemask Top")
		(15 "B.Paste" user "Package Geometry/Pastemask Bottom")
		(5 "F.SilkS" user "Ref Des/Silkscreen Top")
		(7 "B.SilkS" user "Ref Des/Silkscreen Bottom")
		(1 "F.Mask" user "Board Geometry/Soldermask Top")
		(3 "B.Mask" user "Board Geometry/Soldermask Bottom")
		(17 "Dwgs.User" user "User.Drawings")
		(19 "Cmts.User" user "User.Comments")
		(21 "Eco1.User" user "User.Eco1")
		(23 "Eco2.User" user "User.Eco2")
		(25 "Edge.Cuts" user "Board Geometry/Outline")
		(27 "Margin" user)
		(31 "F.CrtYd" user "Package Geometry/Place Bound Top")
		(29 "B.CrtYd" user "Package Geometry/Place Bound Bottom")
		(35 "F.Fab" user "Ref Des/Assembly Top")
		(33 "B.Fab" user "Ref Des/Assembly Bottom")
	)
	(footprint ""
		(layer "B.Cu")
		(at 245.7323 -149.8092 -90)
		(property "Reference" "C5G59"
			(at -1.14681 0.76708 0)
			(unlocked yes)
			(layer "B.SilkS")
			(effects
				(font
					(size 0.7874 0.5842)
					(thickness 0.1524)
				)
				(justify mirror)
			)
		)
		(property "Value" ""
			(at 0 0 90)
			(layer "B.Fab")
			(effects
				(font
					(size 1.27 1.27)
				)
				(justify mirror)
			)
		)
		(duplicate_pad_numbers_are_jumpers no)
		(fp_rect
			(start 0.4953 1.6002)
			(end -0.4953 -0.2032)
			(stroke
				(width 0)
				(type default)
			)
			(fill no)
			(layer "B.CrtYd")
		)
		(fp_line
			(start -0.4953 1.6002)
			(end 0.4953 1.6002)
			(stroke
				(width 0.1)
				(type default)
			)
			(layer "B.Fab")
		)
		(fp_line
			(start 0.4953 1.6002)
			(end 0.4953 -0.2032)
			(stroke
				(width 0.1)
				(type default)
			)
			(layer "B.Fab")
		)
		(fp_line
			(start -0.4953 -0.2032)
			(end -0.4953 1.6002)
			(stroke
				(width 0.1)
				(type default)
			)
			(layer "B.Fab")
		)
		(fp_line
			(start 0.4953 -0.2032)
			(end -0.4953 -0.2032)
			(stroke
				(width 0.1)
				(type default)
			)
			(layer "B.Fab")
		)
		(pad "1" smd rect
			(at 0 0 90)
			(size 0.762 0.889)
			(layers "B.Cu" "B.Mask" "B.Paste")
			(net "PVDDQ_DEF")
		)
		(pad "2" smd rect
			(at 0 1.397 90)
			(size 0.762 0.889)
			(layers "B.Cu" "B.Mask" "B.Paste")
			(net "GND")
		)
		(zone
			(layer "B.Cu")
			(hatch none 0.5)
			(connect_pads
				(clearance 0)
			)
			(min_thickness 0.25)
			(keepout
				(tracks not_allowed)
				(vias allowed)
				(pads allowed)
				(copperpour not_allowed)
				(footprints allowed)
			)
			(placement
				(enabled no)
				(sheetname "")
			)
			(fill
				(thermal_gap 0.5)
				(thermal_bridge_width 0.5)
				(island_removal_mode 0)
			)
			(polygon
				(pts
					(xy 244.7798 -149.4282) (xy 245.2878 -149.4282) (xy 245.2878 -150.1902) (xy 244.7798 -150.1902)
				)
			)
		)
	)
	(footprint ""
		(layer "B.Cu")
		(at 185.25109 0.139192 180)
		(property "Reference" "C6U15"
			(at 0 0 0)
			(layer "B.SilkS")
			(hide yes)
			(effects
				(font
					(size 1.27 1.27)
				)
				(justify mirror)
			)
		)
		(property "Value" ""
			(at 0 0 0)
			(layer "B.Fab")
			(effects
				(font
					(size 1.27 1.27)
				)
				(justify mirror)
			)
		)
		(duplicate_pad_numbers_are_jumpers no)
		(fp_rect
			(start 0.4953 -0.2032)
			(end -0.4953 1.6002)
			(stroke
				(width 0)
				(type default)
			)
			(fill no)
			(layer "B.CrtYd")
		)
		(fp_line
			(start 0.4953 1.6002)
			(end 0.4953 -0.2032)
			(stroke
				(width 0.1)
				(type default)
			)
			(layer "B.Fab")
		)
		(fp_line
			(start 0.4953 -0.2032)
			(end -0.4953 -0.2032)
			(stroke
				(width 0.1)
				(type default)
			)
			(layer "B.Fab")
		)
		(fp_line
			(start -0.4953 1.6002)
			(end 0.4953 1.6002)
			(stroke
				(width 0.1)
				(type default)
			)
			(layer "B.Fab")
		)
		(fp_line
			(start -0.4953 -0.2032)
			(end -0.4953 1.6002)
			(stroke
				(width 0.1)
				(type default)
			)
			(layer "B.Fab")
		)
		(pad "1" smd rect
			(at 0 0)
			(size 0.762 0.889)
			(layers "B.Cu" "B.Mask" "B.Paste")
			(net "PVDDQ_ABC")
		)
		(pad "2" smd rect
			(at 0 1.397)
			(size 0.762 0.889)
			(layers "B.Cu" "B.Mask" "B.Paste")
			(net "GND")
		)
		(zone
			(layer "B.Cu")
			(hatch none 0.5)
			(connect_pads
				(clearance 0)
			)
			(min_thickness 0.25)
			(keepout
				(tracks not_allowed)
				(vias allowed)
				(pads allowed)
				(copperpour not_allowed)
				(footprints allowed)
			)
			(placement
				(enabled no)
				(sheetname "")
			)
			(fill
				(thermal_gap 0.5)
				(thermal_bridge_width 0.5)
				(island_removal_mode 0)
			)
			(polygon
				(pts
					(xy 184.87009 -0.305308) (xy 185.63209 -0.305308) (xy 185.63209 -0.813308) (xy 184.87009 -0.813308)
				)
			)
		)
	)
	(footprint ""
		(layer "B.Cu")
		(at 476.1738 -45.6438 -90)
		(property "Reference" "C22W34"
			(at 0 0 90)
			(layer "B.SilkS")
			(hide yes)
			(effects
				(font
					(size 1.27 1.27)
				)
				(justify mirror)
			)
		)
		(property "Value" "*"
			(at 0.0762 -6.2357 270)
			(unlocked yes)
			(layer "B.Fab")
			(hide yes)
			(effects
				(font
					(size 1.27 1.016)
					(thickness 0.1524)
				)
				(justify mirror)
			)
		)
		(property "Device Type" "SC22U16V5MX-4-GP_SMD-BCG5-SC22A"
			(at 0.0762 -8.2677 270)
			(unlocked yes)
			(layer "B.Fab")
			(hide yes)
			(effects
				(font
					(size 1.27 1.016)
					(thickness 0.1524)
				)
				(justify mirror)
			)
		)
		(duplicate_pad_numbers_are_jumpers no)
		(fp_line
			(start -0.635 0)
			(end 0.635 0)
			(stroke
				(width 0.508)
				(type default)
			)
			(layer "B.SilkS")
		)
		(fp_rect
			(start 0.9652 1.778)
			(end -0.9652 -1.778)
			(stroke
				(width 0)
				(type default)
			)
			(fill no)
			(layer "B.CrtYd")
		)
		(fp_poly
			(pts
				(xy 0.9652 -1.778) (xy -0.9652 -1.778) (xy -0.9652 1.778) (xy 0.9652 1.778)
			)
			(stroke
				(width 0)
				(type default)
			)
			(fill no)
			(layer "B.Fab")
		)
		(pad "1" smd rect
			(at 0 -0.9652 90)
			(size 1.397 1.143)
			(layers "B.Cu" "B.Mask" "B.Paste")
			(net "P3V3_STBY")
		)
		(pad "2" smd rect
			(at 0 0.9652 90)
			(size 1.397 1.143)
			(layers "B.Cu" "B.Mask" "B.Paste")
			(net "GND")
		)
	)
	(footprint ""
		(layer "B.Cu")
		(at 49.4284 -59.143392 180)
		(property "Reference" "C9R8"
			(at 0 0 0)
			(layer "B.SilkS")
			(hide yes)
			(effects
				(font
					(size 1.27 1.27)
				)
				(justify mirror)
			)
		)
		(property "Value" ""
			(at 0 0 0)
			(layer "B.Fab")
			(effects
				(font
					(size 1.27 1.27)
				)
				(justify mirror)
			)
		)
		(duplicate_pad_numbers_are_jumpers no)
		(fp_poly
			(pts
				(xy 0.4953 -0.2032) (xy -0.4953 -0.2032) (xy -0.4953 1.6002) (xy 0.4953 1.6002)
			)
			(stroke
				(width 0)
				(type default)
			)
			(fill no)
			(layer "B.CrtYd")
		)
		(fp_line
			(start 0.4953 1.6002)
			(end 0.4953 -0.2032)
			(stroke
				(width 0.1)
				(type default)
			)
			(layer "B.Fab")
		)
		(fp_line
			(start 0.4953 -0.2032)
			(end -0.4953 -0.2032)
			(stroke
				(width 0.1)
				(type default)
			)
			(layer "B.Fab")
		)
		(fp_line
			(start -0.4953 1.6002)
			(end 0.4953 1.6002)
			(stroke
				(width 0.1)
				(type default)
			)
			(layer "B.Fab")
		)
		(fp_line
			(start -0.4953 -0.2032)
			(end -0.4953 1.6002)
			(stroke
				(width 0.1)
				(type default)
			)
			(layer "B.Fab")
		)
		(pad "1" smd rect
			(at 0 0)
			(size 0.762 0.889)
			(layers "B.Cu" "B.Mask" "B.Paste")
			(net "PVCCIN_CPU1")
		)
		(pad "2" smd rect
			(at 0 1.397)
			(size 0.762 0.889)
			(layers "B.Cu" "B.Mask" "B.Paste")
			(net "GND")
		)
		(zone
			(layer "B.Cu")
			(hatch none 0.5)
			(connect_pads
				(clearance 0)
			)
			(min_thickness 0.25)
			(keepout
				(tracks not_allowed)
				(vias allowed)
				(pads allowed)
				(copperpour not_allowed)
				(footprints allowed)
			)
			(placement
				(enabled no)
				(sheetname "")
			)
			(fill
				(thermal_gap 0.5)
				(thermal_bridge_width 0.5)
				(island_removal_mode 0)
			)
			(polygon
				(pts
					(xy 49.0474 -59.587892) (xy 49.8094 -59.587892) (xy 49.8094 -60.095892) (xy 49.0474 -60.095892)
				)
			)
		)
	)
)
